# T6G (Grand Teton) — schematic parts with pin connectivity, parts 7740–7889 of 8303; source: Cadence DE-HDL packaged netlist (pstxprt.dat, pstxnet.dat, pstchip.dat)

R6764  Q_RES  1K 1% CHIP  pkg 0201LF  page 184 : 1 = P1V8_CPU0_RT_1D ; 2 = SMB_RT_CPU0_P1_R_SDA
R6765  Q_RES  1K 1% CHIP  pkg 0201LF  page 184 : 1 = P1V8_CPU0_RT_1D ; 2 = SMB_RT_CPU0_P1_R_SCL
R6766  Q_RES  1K 1% CHIP  pkg 0201LF  page 184 : 1 = P1V8_CPU0_RT_1D ; 2 = SMB_RT_CPU0_P3_R_SDA
R6767  Q_RES  1K 1% CHIP  pkg 0201LF  page 184 : 1 = P1V8_CPU0_RT_1D ; 2 = SMB_RT_CPU0_P3_R_SCL
R6768  Q_RES  1K 1% CHIP  pkg 0201LF  page 184 : 1 = P1V8_CPU0_RT_1D ; 2 = SMB_RT_CPU0_P2_R_SDA
R6769  Q_RES  1K 1% CHIP  pkg 0201LF  page 184 : 1 = P1V8_CPU0_RT_1D ; 2 = SMB_RT_CPU0_P2_R_SCL
R6770  Q_RES  4.7K 5% EMPTY  pkg 0201LF  page 184 : 1 = P1V8_AUX ; 2 = RT_SMB_MUX_ADDR2
R6771  Q_RES  4.7K 5% EMPTY  pkg 0201LF  page 184 : 1 = P1V8_AUX ; 2 = RT_SMB_MUX_ADDR1
R6772  Q_RES  4.7K 5% EMPTY  pkg 0201LF  page 184 : 1 = P1V8_AUX ; 2 = RT_SMB_MUX_ADDR0
R6773  Q_RES  4.7K 5% CHIP  pkg 0201LF  page 184 : 1 = RT_SMB_MUX_ADDR2 ; 2 = GND
R6774  Q_RES  4.7K 5% CHIP  pkg 0201LF  page 184 : 1 = RT_SMB_MUX_ADDR1 ; 2 = GND
R6775  Q_RES  4.7K 5% CHIP  pkg 0201LF  page 184 : 1 = RT_SMB_MUX_ADDR0 ; 2 = GND
R6776  Q_RES  0 5% CHIP  pkg 0201LF  page 184 : 1 = RST_SMB_RT_R1_N ; 2 = RST_SMB_RT_N
R6777  Q_RES  0 5% CHIP  pkg 0402LF  page 81 : 1 = RST_SMB_RT_R2_N ; 2 = RST_SMB_RT_R1_N
R6778  Q_RES  10K 1% CHIP  pkg 0201LF  page 184 : 1 = RST_SMB_RT_R1_N ; 2 = GND
R6779  Q_RES  33.2 1% CHIP  pkg 0201LF  page 184 : 1 = SMB_MUX_RT_SDA ; 2 = SMB_MUX_RT_R1_SDA
R6780  Q_RES  33.2 1% CHIP  pkg 0201LF  page 184 : 1 = SMB_MUX_RT_SCL ; 2 = SMB_MUX_RT_R1_SCL
R6781  Q_RES  0 5% CHIP  pkg 0402LF  page 81 : 1 = RST_SMB_RT_ROM_R2_N ; 2 = RST_SMB_RT_ROM_R1_N
R6782  Q_RES  33 5% CHIP  pkg 0402LF  page 151 : 1 = SMB_MUX_RT_ROM_R1_SCL ; 2 = SMB_HOST_CLK_3V3AUX_SCL_R1
R6783  Q_RES  33 5% CHIP  pkg 0402LF  page 151 : 1 = SMB_MUX_RT_ROM_R1_SDA ; 2 = SMB_HOST_CLK_3V3AUX_SDA_R1
R6784  Q_RES  0 5% CHIP  pkg 0402LF  page 151 : 1 = SMB_MUX_RT_R1_SCL ; 2 = SMB_SML1_PMBUS_HSC_SCL
R6785  Q_RES  0 5% CHIP  pkg 0402LF  page 151 : 1 = SMB_MUX_RT_R1_SDA ; 2 = SMB_SML1_PMBUS_HSC_SDA
R6786  Q_RES  1K 1% CHIP  pkg 0402LF  page 362 : 1 = P0V9_RETIMER_CPU0_EN0_R ; 2 = GND
R6787  Q_RES  1K 1% CHIP  pkg 0402LF  page 364 : 1 = P0V9_RETIMER_CPU1_EN0_R ; 2 = GND
R6788  Q_RES  1K 1% CHIP  pkg 0201LF  page 322 : 1 = U12_E2 ; 2 = GND
R6789  Q_RES  1K 1% CHIP  pkg 0201LF  page 333 : 1 = U19_E2 ; 2 = GND
R6790  Q_RES  1K 1% CHIP  pkg 0201LF  page 344 : 1 = U20_E2 ; 2 = GND
R6791  Q_RES  1K 1% CHIP  pkg 0201LF  page 355 : 1 = U21_E2 ; 2 = GND
R6792  Q_RES  0 5% CHIP  pkg 0402LF  page 81 : 1 = RST_RT_CPU1_P2_PERST_R_N ; 2 = RST_RT_CPU1_P2_PERST_R2_N
R6793  Q_RES  0 5% CHIP  pkg 0402LF  page 81 : 1 = RST_RT_CPU1_P2_RESET_R_N ; 2 = RST_RT_CPU1_P2_RESET_R2_N
R6794  Q_RES  1K 1% EMPTY  pkg 0201LF  page 343 : 1 = P1V8_CPU1_RT_1D ; 2 = RT_CPU1_P2_VQPS
R6795  Q_RES  200 1% CHIP  pkg 0201LF  page 343 : 1 = RT_CPU1_P2_VQPS ; 2 = GND
R6796  Q_RES  0 5% CHIP  pkg 0201LF  page 343 : 1 = NCF_A1_CPU1_P2_GND ; 2 = GND
R6797  Q_RES  0 5% CHIP  pkg 0201LF  page 343 : 1 = NCF_CPU1_P2_GND ; 2 = GND
R6798  Q_RES  0 5% CHIP  pkg 0402LF  page 81 : 1 = RST_RT_CPU1_P3_PERST_R_N ; 2 = RST_RT_CPU1_P3_PERST_R2_N
R6799  Q_RES  0 5% CHIP  pkg 0402LF  page 81 : 1 = RST_RT_CPU1_P3_RESET_R_N ; 2 = RST_RT_CPU1_P3_RESET_R2_N
R6800  Q_RES  0 5% CHIP  pkg 0402LF  page 364 : 1 = GND ; 2 = P0V9_RETIMER_CPU1_EN1_R
R6801  Q_RES  0 5% CHIP  pkg 0402LF  page 362 : 1 = GND ; 2 = P0V9_RETIMER_CPU0_EN1_R
R6802  Q_RES  10K 1% CHIP  pkg 0402LF  page 182 : 1 = FM_9ZXL045_P0_3_OE_N ; 2 = GND
R6803  Q_RES  10K 1% CHIP  pkg 0402LF  page 183 : 1 = FM_9ZXL045_P1_3_OE_N ; 2 = GND
R6804  Q_RES  0 5% CHIP  pkg 0402LF  page 81 : 1 = RST_RT_CPU0_P0_PERST_R_N ; 2 = RST_RT_CPU0_P0_PERST_R2_N
R6805  Q_RES  0 5% CHIP  pkg 0402LF  page 81 : 1 = RST_RT_CPU0_P0_RESET_R_N ; 2 = RST_RT_CPU0_P0_RESET_R2_N
R6806  Q_RES  0 5% CHIP  pkg 0402LF  page 81 : 1 = RST_RT_CPU0_P1_PERST_R_N ; 2 = RST_RT_CPU0_P1_PERST_R2_N
R6807  Q_RES  0 5% CHIP  pkg 0402LF  page 81 : 1 = RST_RT_CPU0_P1_RESET_R_N ; 2 = RST_RT_CPU0_P1_RESET_R2_N
R6808  Q_RES  1K 1% EMPTY  pkg 0201LF  page 277 : 1 = P1V8_CPU0_RT_1D ; 2 = RT_CPU0_P0_VQPS
R6809  Q_RES  200 1% CHIP  pkg 0201LF  page 277 : 1 = RT_CPU0_P0_VQPS ; 2 = GND
R6810  Q_RES  0 5% CHIP  pkg 0201LF  page 184 : 1 = SMB_RT_CPU1_P0_R_SDA ; 2 = SMB_RT_CPU1_P0_SDA
R6811  Q_RES  0 5% CHIP  pkg 0201LF  page 184 : 1 = SMB_RT_CPU1_P0_R_SCL ; 2 = SMB_RT_CPU1_P0_SCL
R6812  Q_RES  0 5% CHIP  pkg 0201LF  page 320 : 1 = SMB_RT_CPU1_P0_R_SCL ; 2 = SMB_RT_CPU1_P0_R2_SCL
R6813  Q_RES  0 5% CHIP  pkg 0201LF  page 320 : 1 = SMB_RT_CPU1_P0_R_SDA ; 2 = SMB_RT_CPU1_P0_R2_SDA
R6820  Q_RES  0 5% CHIP  pkg 0201LF  page 277 : 1 = NCF_A1_CPU0_P0_GND ; 2 = GND
R6821  Q_RES  0 5% CHIP  pkg 0201LF  page 277 : 1 = NCF_CPU0_P0_GND ; 2 = GND
R6822  Q_RES  1K 1% CHIP  pkg 0201LF  page 278 : 1 = U11_E2 ; 2 = GND
R6823  Q_RES  0 5% CHIP  pkg 0402LF  page 81 : 1 = RST_RT_CPU0_P2_PERST_R2_N ; 2 = RST_RT_CPU0_P2_PERST_R_N
R6824  Q_RES  0 5% CHIP  pkg 0402LF  page 81 : 1 = RST_RT_CPU0_P2_RESET_R2_N ; 2 = RST_RT_CPU0_P2_RESET_R_N
R6825  Q_RES  0 5% CHIP  pkg 0402LF  page 81 : 1 = RST_RT_CPU0_P3_PERST_R2_N ; 2 = RST_RT_CPU0_P3_PERST_R_N
R6826  Q_RES  0 5% CHIP  pkg 0402LF  page 81 : 1 = RST_RT_CPU0_P3_RESET_R2_N ; 2 = RST_RT_CPU0_P3_RESET_R_N
R6850  Q_RES  33 5% CHIP  pkg 0402LF  page 80 : 1 = P1V8_RETIMER_CPU0_EN ; 2 = P1V8_RETIMER_CPU0_R_EN
R6851  Q_RES  33 5% CHIP  pkg 0402LF  page 80 : 1 = P1V8_RETIMER_CPU1_EN ; 2 = P1V8_RETIMER_CPU1_R_EN
R6852  Q_RES  0 5% CHIP  pkg 0402LF  page 81 : 1 = PWRGD_P0V9_RETIMER_CPU0 ; 2 = PWRGD_P0V9_RETIMER_CPU0_R2
R6853  Q_RES  0 5% CHIP  pkg 0402LF  page 81 : 1 = PWRGD_P0V9_RETIMER_CPU1 ; 2 = PWRGD_P0V9_RETIMER_CPU1_R2
R6854  Q_RES  33 5% CHIP  pkg 0402LF  page 81 : 1 = P0V9_RETIMER_CPU0_EN ; 2 = P0V9_RETIMER_CPU0_EN_R2
R6855  Q_RES  33 5% CHIP  pkg 0402LF  page 81 : 1 = P0V9_RETIMER_CPU1_EN_R2 ; 2 = P0V9_RETIMER_CPU1_EN
R6856  Q_RES  33 5% CHIP  pkg 0402LF  page 151 : 1 = SMB_SCM_2_R6_SCL ; 2 = P0V9_RETIMER_CPU0_PMSCL
R6857  Q_RES  33 5% CHIP  pkg 0402LF  page 151 : 1 = SMB_SCM_2_R6_SDA ; 2 = P0V9_RETIMER_CPU0_PMSDA
R6858  Q_RES  0 5% CHIP  pkg 0402LF  page 151 : 1 = SMB_VR_3V3STBY_SCL ; 2 = P0V9_RETIMER_CPU1_PMSCL
R6859  Q_RES  0 5% CHIP  pkg 0402LF  page 151 : 1 = SMB_VR_3V3STBY_SDA ; 2 = P0V9_RETIMER_CPU1_PMSDA
R6860  Q_RES  1K 1% CHIP  pkg 0402LF  page 362 : 1 = P1V8_AUX ; 2 = PWRGD_P0V9_RETIMER_CPU0_R
R6861  Q_RES  1K 1% CHIP  pkg 0402LF  page 364 : 1 = P1V8_AUX ; 2 = PWRGD_P0V9_RETIMER_CPU1_R
R6862  Q_RES  33 5% CHIP  pkg 0402LF  page 151 : 1 = SMB_HOST_CLK_3V3AUX_SCL_R1 ; 2 = SMB_9ZXL045_P1_SCL
R6863  Q_RES  33 5% CHIP  pkg 0402LF  page 151 : 1 = SMB_HOST_CLK_3V3AUX_SDA_R1 ; 2 = SMB_9ZXL045_P1_SDA
R6864  Q_RES  33 5% CHIP  pkg 0402LF  page 151 : 1 = SMB_HOST_CLK_3V3AUX_SCL_R1 ; 2 = SMB_9ZXL045_P0_SCL
R6865  Q_RES  33 5% CHIP  pkg 0402LF  page 151 : 1 = SMB_HOST_CLK_3V3AUX_SDA_R1 ; 2 = SMB_9ZXL045_P0_SDA
R6900  Q_RES  1K 1% EMPTY  pkg 0201LF  page 354 : 1 = P1V8_CPU1_RT_1D ; 2 = RT_CPU1_P3_VQPS
R6901  Q_RES  200 1% CHIP  pkg 0201LF  page 354 : 1 = RT_CPU1_P3_VQPS ; 2 = GND
R6902  Q_RES  0 5% CHIP  pkg 0201LF  page 354 : 1 = NCF_A1_CPU1_P3_GND ; 2 = GND
R6903  Q_RES  0 5% CHIP  pkg 0201LF  page 354 : 1 = NCF_CPU1_P3_GND ; 2 = GND
R8000  Q_RES  33.2 1% CHIP  pkg 0402LF  page 81 : 1 = PRSNT_SWB_ISO_N ; 2 = PRSNT_SWB_ISO_R_N
R8001  Q_RES  100K 1% EMPTY  pkg 0402LF  page 123 : 1 = PRSNT_SWB_N ; 2 = GND
R8002  Q_RES  4.7K 5% CHIP  pkg 0402LF  page 123 : 1 = P3V3_AUX ; 2 = PRSNT_SWB
R8003  Q_RES  4.7K 5% CHIP  pkg 0402LF  page 123 : 1 = P3V3_AUX ; 2 = PRSNT_SWB_ISO_N
R8004  Q_RES  0 5% CHIP  pkg 0402LF  page 245 : 1 = PRSNT_SWB_ISO_N ; 2 = PRSNT_SWB_ISO_R1_N
R8005  Q_RES  33 5% CHIP  pkg 0402LF  page 77 : 1 = SPI_CPU0_D3 ; 2 = SPI_CPU0_R1_D3
R8006  Q_RES  33 5% CHIP  pkg 0402LF  page 77 : 1 = SPI_CPU0_D2 ; 2 = SPI_CPU0_R1_D2
R8007  Q_RES  33 5% CHIP  pkg 0402LF  page 77 : 1 = SPI_CPU0_D0 ; 2 = SPI_CPU0_R1_D0
R8008  Q_RES  33 5% CHIP  pkg 0402LF  page 77 : 1 = SPI_CPU0_D1 ; 2 = SPI_CPU0_R1_D1
R8009  Q_RES  10K 5% CHIP  pkg 0402LF  page 226 : 1 = P3V3_AUX ; 2 = PWRGD_PVDD18_S5_P1
R8010  Q_RES  0 5% EMPTY  pkg 0402LF  page 224 : 1 = PVDD11_S3_P1_OCP_N ; 2 = PVDD11_S3_P1_OCP_N_R
R8011  Q_RES  1K 1% EMPTY  pkg 0402LF  page 224 : 1 = PVDD18_S5_P1 ; 2 = PVDD11_S3_P1_OCP_N_R
R8012  Q_RES  0 5% CHIP  pkg 0402LF  page 152 : 1 = HP_LVC3_SCM_HSC_PWRGD_R ; 2 = HP_LVC3_SCM_HSC_PWRGD
R8013  Q_RES  0 5% EMPTY  pkg 0402LF  page 143 : 1 = OCP_SFF_PRSNT01_R_N ; 2 = OCP_SFF_PRSNT01_R1_N
R8014  Q_RES  0 5% EMPTY  pkg 0402LF  page 143 : 1 = OCP_SFF_PRSNT23_R_N ; 2 = OCP_SFF_PRSNT23_R1_N
R8015  Q_RES  0 5% EMPTY  pkg 0402LF  page 143 : 1 = OCP_V3_2_PRSNT01_R_N ; 2 = OCP_V3_2_PRSNT01_R1_N
R8016  Q_RES  0 5% EMPTY  pkg 0402LF  page 143 : 1 = OCP_V3_2_PRSNT23_R_N ; 2 = OCP_V3_2_PRSNT23_R1_N
R8017  Q_RES  0 5% EMPTY  pkg 0402LF  page 167 : 1 = P3V3_AUX ; 2 = U124_VCC
R8018  Q_RES  0 5% CHIP  pkg 0402LF  page 167 : 1 = P1V8_AUX ; 2 = U124_VCC
R8019  Q_RES  100 1% EMPTY  pkg 0402LF  page 167 : 1 = P3V3_AUX ; 2 = FM_JTAG_BMC_R_OE
R8021  Q_RES  0 5% CHIP  pkg 0402LF  page 81 : 1 = FM_JTAG_BMC_OE ; 2 = FM_JTAG_BMC_R_OE
R8022  Q_RES  560 1% CHIP  pkg 0402LF  page 256 : 1 = LED_P12V_AUX_R1 ; 2 = LED_P12V_AUX_R2
R8023  Q_RES  560 1% CHIP  pkg 0402LF  page 256 : 1 = LED_P12V_AUX_R2 ; 2 = LED_P12V_AUX_R3
R8024  Q_RES  560 1% CHIP  pkg 0402LF  page 256 : 1 = LED_P12V_AUX_R3 ; 2 = P12V_AUX
R8025  Q_RES  560 1% CHIP  pkg 0402LF  page 256 : 1 = LED_P12V_PSU_R1 ; 2 = LED_P12V_PSU_R2
R8026  Q_RES  560 1% CHIP  pkg 0402LF  page 256 : 1 = LED_P12V_PSU_R2 ; 2 = LED_P12V_PSU_R3
R8027  Q_RES  560 1% CHIP  pkg 0402LF  page 256 : 1 = LED_P12V_PSU_R3 ; 2 = P12V_PSU
R8028  Q_RES  4.7K 5% CHIP  pkg 0402LF  page 256 : 1 = P3V3_AUX ; 2 = LED_P12V_SCM_FAULT_D1
R8029  Q_RES  249 1% CHIP  pkg 0402LF  page 256 : 1 = LED_P12V_SCM_FAULT ; 2 = P3V3_AUX
R8030  Q_RES  0 5% CHIP  pkg 0402LF  page 152 : 1 = P12V_SCM_FAULT_N ; 2 = P12V_SCM_FAULT_R_N
R8031  Q_RES  0 5% CHIP  pkg 0402LF  page 152 : 1 = P12V_SCM_FLTB_N ; 2 = P12V_SCM_FAULT_R_N
R8032  Q_RES  0 5% CHIP  pkg 0402LF  page 81 : 1 = FM_ESPI_CPU0_ALERT_SEL ; 2 = FM_ESPI_CPU0_ALERT_R_SEL
R8033  Q_RES  1K 1% CHIP  pkg 0402LF  page 83 : 1 = FM_ESPI_CPU0_ALERT_R_SEL ; 2 = GND
R8034  Q_RES  0 5% CHIP  pkg 0402LF  page 153 : 1 = ESPI_CPU0_ALERT_R1_N ; 2 = ESPI_CPU0_ALERT_N
R8035  Q_RES  4.7K 5% EMPTY  pkg 0402LF  page 153 : 1 = P1V8_AUX ; 2 = ESPI_CPU0_ALERT_N
R8036  Q_RES  4.7K 5% EMPTY  pkg 0402LF  page 153 : 1 = PVDD18_S5_P0 ; 2 = ESPI_CPU0_ALERT_PLD_N
R8037  Q_RES  10K 1% CHIP  pkg 0402LF  page 86 : 1 = P3V3_AUX ; 2 = PWRGD_CHAF_CPU0
R8038  Q_RES  10K 1% CHIP  pkg 0402LF  page 92 : 1 = P3V3_AUX ; 2 = PWRGD_CHGL_CPU0
R8039  Q_RES  10K 1% CHIP  pkg 0402LF  page 98 : 1 = P3V3_AUX ; 2 = PWRGD_CHAF_CPU1
R8040  Q_RES  10K 1% CHIP  pkg 0402LF  page 104 : 1 = P3V3_AUX ; 2 = PWRGD_CHGL_CPU1
R8042  Q_RES  1K 1% EMPTY  pkg 0402LF  page 200 : 1 = SVID_PVDDCR_CPU1_P0_SVTO ; 2 = GND
R8043  Q_RES  1K 1% EMPTY  pkg 0402LF  page 200 : 1 = PVDD18_S5_P0 ; 2 = SVID_PVDDCR_CPU1_P0_SVTO
R8045  Q_RES  1K 1% EMPTY  pkg 0402LF  page 200 : 1 = PVDD18_S5_P0 ; 2 = SVID_PVDDCR_CPU1_P0_SVD_R
R8047  Q_RES  0 5% CHIP  pkg 0402LF  page 200 : 1 = PVDDIO_P0_EN ; 2 = PVDDIO_P0_EN_R
R8048  Q_RES  1K 1% EMPTY  pkg 0402LF  page 200 : 1 = PVDD18_S5_P0 ; 2 = SVID_PVDDCR_CPU1_P0_SVC_R
R8056  Q_RES  1K 1% CHIP  pkg 0402LF  page 200 : 1 = P3V3_AUX ; 2 = PWRGD_PVDDCR_CPU1_P0_R
R8057  Q_RES  33 5% CHIP  pkg 0402LF  page 200 : 1 = PWRGD_PVDDCR_CPU1_P0 ; 2 = PWRGD_PVDDCR_CPU1_P0_R
R8058  Q_RES  0 5% CHIP  pkg 0402LF  page 200 : 1 = FM_PVDDCR_CPU1_P0_EN ; 2 = PVDDCR_CPU1_P0_EN_R
R8063  Q_RES  100 1% CHIP  pkg 0402LF  page 200 : 1 = PVDDCR_CPU1_P0_RESET_N ; 2 = PVDDCR_CPU1_P0_RESET_N_R
R8064  Q_RES  0 5% CHIP  pkg 0402LF  page 200 : 1 = PVDDCR_CPU1_P0_OCP_N ; 2 = PVDDCR_CPU1_P0_OCP_N_R
R8065  Q_RES  1K 1% CHIP  pkg 0402LF  page 200 : 1 = P3V3_AUX ; 2 = PWRGD_PVDDIO_P0_R
R8066  Q_RES  33 5% CHIP  pkg 0402LF  page 200 : 1 = PWRGD_PVDDIO_P0 ; 2 = PWRGD_PVDDIO_P0_R
R8070  Q_RES  1K 1% CHIP  pkg 0402LF  page 200 : 1 = PVDD18_S5_P0 ; 2 = PVDDCR_CPU1_P0_RESET_N_R
R8071  Q_RES  0 5% CHIP  pkg 0402LF  page 200 : 1 = SMB_SCM_2_R5_SCL ; 2 = SMB_CLK_PVDDCR_CPU1_P0_R
R8072  Q_RES  0 5% CHIP  pkg 0402LF  page 200 : 1 = SMB_SCM_2_R5_SDA ; 2 = SMB_DIO_PVDDCR_CPU1_P0_R
R8073  Q_RES  33 5% CHIP  pkg 0402LF  page 200 : 1 = PVDDCR_CPU1_P0_SMB_ALERT ; 2 = PVDDCR_CPU1_P0_SMB_ALERT_R
R8075  Q_RES  1K 1% CHIP  pkg 0402LF  page 200 : 1 = PVDD18_S5_P0 ; 2 = PVDDCR_CPU1_P0_OCP_N_R
R8080  Q_RES  0 5% CHIP  pkg 0402LF  page 86 : 1 = PWRGD_CHAF_CPU0 ; 2 = PWRGD_CHAF_CPU0_R1
R8081  Q_RES  0 5% CHIP  pkg 0402LF  page 86 : 1 = PWRGD_CHAF_CPU0_R1 ; 2 = PWRGD_CHAF_CPU0_R2
R8082  Q_RES  10K 1% EMPTY  pkg 0402LF  page 86 : 1 = P3V3_AUX ; 2 = PWRGD_CHAF_CPU0_R1
R8083  Q_RES  0 5% CHIP  pkg 0402LF  page 92 : 1 = PWRGD_CHGL_CPU0 ; 2 = PWRGD_CHGL_CPU0_R1
R8084  Q_RES  0 5% CHIP  pkg 0402LF  page 92 : 1 = PWRGD_CHGL_CPU0_R1 ; 2 = PWRGD_CHGL_CPU0_R2
R8085  Q_RES  10K 1% EMPTY  pkg 0402LF  page 92 : 1 = P3V3_AUX ; 2 = PWRGD_CHGL_CPU0_R1
R8086  Q_RES  0 5% CHIP  pkg 0402LF  page 98 : 1 = PWRGD_CHAF_CPU1 ; 2 = PWRGD_CHAF_CPU1_R1
R8087  Q_RES  0 5% CHIP  pkg 0402LF  page 98 : 1 = PWRGD_CHAF_CPU1_R1 ; 2 = PWRGD_CHAF_CPU1_R2
R8088  Q_RES  10K 1% EMPTY  pkg 0402LF  page 98 : 1 = P3V3_AUX ; 2 = PWRGD_CHAF_CPU1_R1
R8089  Q_RES  0 5% CHIP  pkg 0402LF  page 104 : 1 = PWRGD_CHGL_CPU1 ; 2 = PWRGD_CHGL_CPU1_R1
R8090  Q_RES  0 5% CHIP  pkg 0402LF  page 104 : 1 = PWRGD_CHGL_CPU1_R1 ; 2 = PWRGD_CHGL_CPU1_R2
R8091  Q_RES  10K 1% EMPTY  pkg 0402LF  page 104 : 1 = P3V3_AUX ; 2 = PWRGD_CHGL_CPU1_R1
R8092  Q_RES  10K 5% EMPTY  pkg 0402LF  page 136 : 1 = P3V3_OCP_SFF_R ; 2 = OCP_V3_1_P3V3_R1_PWRGD
R8093  Q_RES  100K 1% CHIP  pkg 0402LF  page 136 : 1 = OCP_V3_1_P3V3_R1_PWRGD ; 2 = GND
R8094  Q_RES  0 5% CHIP  pkg 0402LF  page 136 : 1 = OCP_V3_1_P3V3_R1_PWRGD ; 2 = OCP_V3_1_P3V3_PWRGD
R8095  Q_RES  10K 5% EMPTY  pkg 0402LF  page 142 : 1 = P3V3_OCP_V3_2_R ; 2 = OCP_V3_2_P3V3_R1_PWRGD
